# T6G (Grand Teton) — schematic netlist excerpt (pin names and nets, part order shuffled) for the footprints in the layout excerpt that follows; sources: Cadence DE-HDL packaged netlist, KiCad conversion of 04192023_DAF0TMB3IC0_F0TG_MB_C_brd_V02_OCP.brd

R6801  Q_RES  0 5% CHIP  pkg 0402LF  page 362 : A = GND ; B = P0V9_RETIMER_CPU0_EN1_R
PC384_1  Q_CAP  22UF 16V 20% X6S  pkg C0805  page 218 : A = SW_P12V_AUX_PVDDCR_CPU1_P1_FLT ; B = GND
C521  Q_CAP  1UF 4V 20% X6S  pkg 0201  page 279 : A = P0V9_CPU0_RT0_2A ; B = GND

(kicad_pcb
	(version 20260206)
	(generator "pcbnew")
	(generator_version "10.0")
	(general
		(thickness 1.6)
		(legacy_teardrops no)
	)
	(paper "A4")
	(title_block
		(title "04192023_DAF0TMB3IC0_F0TG_MB_C_brd_V02_OCP.brd")
		(comment 1 "Grand Teton / footprints 7673-7675 of 8354")
	)
	(layers
		(0 "F.Cu" signal "TOP")
		(4 "In1.Cu" signal "GND")
		(6 "In2.Cu" signal "IN1")
		(8 "In3.Cu" signal "GND1")
		(10 "In4.Cu" signal "IN2")
		(12 "In5.Cu" signal "GND2")
		(14 "In6.Cu" signal "IN3")
		(16 "In7.Cu" signal "GND3")
		(18 "In8.Cu" signal "VCC")
		(20 "In9.Cu" signal "VCC1")
		(22 "In10.Cu" signal "GND4")
		(24 "In11.Cu" signal "IN4")
		(26 "In12.Cu" signal "GND5")
		(28 "In13.Cu" signal "IN5")
		(30 "In14.Cu" signal "GND6")
		(32 "In15.Cu" signal "IN6")
		(34 "In16.Cu" signal "GND7")
		(2 "B.Cu" signal "BOTTOM")
		(9 "F.Adhes" user "F.Adhesive")
		(11 "B.Adhes" user "B.Adhesive")
		(13 "F.Paste" user "Package Geometry/Pastemask Top")
		(15 "B.Paste" user "Package Geometry/Pastemask Bottom")
		(5 "F.SilkS" user "Ref Des/Silkscreen Top")
		(7 "B.SilkS" user "Ref Des/Silkscreen Bottom")
		(1 "F.Mask" user "Board Geometry/Soldermask Top")
		(3 "B.Mask" user "Board Geometry/Soldermask Bottom")
		(17 "Dwgs.User" user "User.Drawings")
		(19 "Cmts.User" user "User.Comments")
		(21 "Eco1.User" user "User.Eco1")
		(23 "Eco2.User" user "User.Eco2")
		(25 "Edge.Cuts" user "Board Geometry/Outline")
		(27 "Margin" user)
		(31 "F.CrtYd" user "Package Geometry/Place Bound Top")
		(29 "B.CrtYd" user "Package Geometry/Place Bound Bottom")
		(35 "F.Fab" user "Ref Des/Assembly Top")
		(33 "B.Fab" user "Ref Des/Assembly Bottom")
	)
	(footprint ""
		(layer "B.Cu")
		(at 439.020966 -420.231824 180)
		(property "Reference" "R6801"
			(at 0 0 0)
			(layer "B.SilkS")
			(hide yes)
			(effects
				(font
					(size 1.27 1.27)
				)
				(justify mirror)
			)
		)
		(property "Value" ""
			(at 0 0 0)
			(layer "B.Fab")
			(effects
				(font
					(size 1.27 1.27)
				)
				(justify mirror)
			)
		)
		(duplicate_pad_numbers_are_jumpers no)
		(fp_line
			(start 0.7874 0.4064)
			(end 0.7874 -0.4064)
			(stroke
				(width 0.1524)
				(type default)
			)
			(layer "B.SilkS")
		)
		(fp_line
			(start 0.7874 -0.4064)
			(end -0.7874 -0.4064)
			(stroke
				(width 0.1524)
				(type default)
			)
			(layer "B.SilkS")
		)
		(fp_line
			(start -0.7874 0.4064)
			(end 0.7874 0.4064)
			(stroke
				(width 0.1524)
				(type default)
			)
			(layer "B.SilkS")
		)
		(fp_line
			(start -0.7874 -0.4064)
			(end -0.7874 0.4064)
			(stroke
				(width 0.1524)
				(type default)
			)
			(layer "B.SilkS")
		)
		(fp_line
			(start 0.67945 0.3048)
			(end 0.67945 -0.305054)
			(stroke
				(width 0.1)
				(type default)
			)
			(layer "B.Fab")
		)
		(fp_line
			(start 0.67945 -0.305054)
			(end 0.12065 -0.305054)
			(stroke
				(width 0.1)
				(type default)
			)
			(layer "B.Fab")
		)
		(fp_line
			(start 0.12065 0.3048)
			(end 0.67945 0.3048)
			(stroke
				(width 0.1)
				(type default)
			)
			(layer "B.Fab")
		)
		(fp_line
			(start 0.12065 0.2794)
			(end 0.12065 0.3048)
			(stroke
				(width 0.1)
				(type default)
			)
			(layer "B.Fab")
		)
		(fp_line
			(start 0.12065 -0.2794)
			(end -0.12065 -0.2794)
			(stroke
				(width 0.1)
				(type default)
			)
			(layer "B.Fab")
		)
		(fp_line
			(start 0.12065 -0.305054)
			(end 0.12065 -0.2794)
			(stroke
				(width 0.1)
				(type default)
			)
			(layer "B.Fab")
		)
		(fp_line
			(start -0.120396 0.3048)
			(end -0.120396 0.2794)
			(stroke
				(width 0.1)
				(type default)
			)
			(layer "B.Fab")
		)
		(fp_line
			(start -0.120396 0.2794)
			(end 0.12065 0.2794)
			(stroke
				(width 0.1)
				(type default)
			)
			(layer "B.Fab")
		)
		(fp_line
			(start -0.12065 -0.2794)
			(end -0.12065 -0.3048)
			(stroke
				(width 0.1)
				(type default)
			)
			(layer "B.Fab")
		)
		(fp_line
			(start -0.12065 -0.3048)
			(end -0.67945 -0.3048)
			(stroke
				(width 0.1)
				(type default)
			)
			(layer "B.Fab")
		)
		(fp_line
			(start -0.67945 0.3048)
			(end -0.120396 0.3048)
			(stroke
				(width 0.1)
				(type default)
			)
			(layer "B.Fab")
		)
		(fp_line
			(start -0.67945 -0.3048)
			(end -0.67945 0.3048)
			(stroke
				(width 0.1)
				(type default)
			)
			(layer "B.Fab")
		)
		(pad "1" smd circle
			(at 0.40005 0)
			(size 0 0)
			(layers "B.Cu" "B.Mask" "B.Paste")
			(net "GND")
		)
		(pad "2" smd circle
			(at -0.40005 0)
			(size 0 0)
			(layers "B.Cu" "B.Mask" "B.Paste")
			(net "P0V9_RETIMER_CPU0_EN1_R")
		)
	)
	(footprint ""
		(layer "B.Cu")
		(at 90.37193 -335.04632 90)
		(property "Reference" "PC384_1"
			(at 0 0 90)
			(layer "B.SilkS")
			(hide yes)
			(effects
				(font
					(size 1.27 1.27)
				)
				(justify mirror)
			)
		)
		(property "Value" ""
			(at 0 0 90)
			(layer "B.Fab")
			(effects
				(font
					(size 1.27 1.27)
				)
				(justify mirror)
			)
		)
		(duplicate_pad_numbers_are_jumpers no)
		(fp_line
			(start 1.524 -0.762)
			(end -1.524 -0.762)
			(stroke
				(width 0.1524)
				(type default)
			)
			(layer "B.SilkS")
		)
		(fp_line
			(start -1.524 -0.762)
			(end -1.524 0.762)
			(stroke
				(width 0.1524)
				(type default)
			)
			(layer "B.SilkS")
		)
		(fp_line
			(start 1.524 0.762)
			(end 1.524 -0.762)
			(stroke
				(width 0.1524)
				(type default)
			)
			(layer "B.SilkS")
		)
		(fp_line
			(start -1.524 0.762)
			(end 1.524 0.762)
			(stroke
				(width 0.1524)
				(type default)
			)
			(layer "B.SilkS")
		)
		(fp_line
			(start 1.1049 -0.724916)
			(end 1.1049 0.724916)
			(stroke
				(width 0.1)
				(type default)
			)
			(layer "B.Fab")
		)
		(fp_line
			(start -1.1049 -0.724916)
			(end 1.1049 -0.724916)
			(stroke
				(width 0.1)
				(type default)
			)
			(layer "B.Fab")
		)
		(fp_line
			(start 1.1049 0.724916)
			(end -1.1049 0.724916)
			(stroke
				(width 0.1)
				(type default)
			)
			(layer "B.Fab")
		)
		(fp_line
			(start -1.1049 0.724916)
			(end -1.1049 -0.724916)
			(stroke
				(width 0.1)
				(type default)
			)
			(layer "B.Fab")
		)
		(pad "1" smd rect
			(at 0.889 0 90)
			(size 1.016 1.27)
			(layers "B.Cu" "B.Mask" "B.Paste")
			(net "SW_P12V_AUX_PVDDCR_CPU1_P1_FLT")
		)
		(pad "2" smd rect
			(at -0.889 0 90)
			(size 1.016 1.27)
			(layers "B.Cu" "B.Mask" "B.Paste")
			(net "GND")
		)
	)
	(footprint ""
		(layer "B.Cu")
		(at 303.378362 -395.148562 90)
		(property "Reference" "C521"
			(at 0 0 90)
			(layer "B.SilkS")
			(hide yes)
			(effects
				(font
					(size 1.27 1.27)
				)
				(justify mirror)
			)
		)
		(property "Value" ""
			(at 0 0 90)
			(layer "B.Fab")
			(effects
				(font
					(size 1.27 1.27)
				)
				(justify mirror)
			)
		)
		(duplicate_pad_numbers_are_jumpers no)
		(fp_line
			(start 0.299974 -0.150114)
			(end -0.299974 -0.150114)
			(stroke
				(width 0.1)
				(type default)
			)
			(layer "B.Fab")
		)
		(fp_line
			(start -0.299974 -0.150114)
			(end -0.299974 0.150114)
			(stroke
				(width 0.1)
				(type default)
			)
			(layer "B.Fab")
		)
		(fp_line
			(start 0.299974 0.150114)
			(end 0.299974 -0.150114)
			(stroke
				(width 0.1)
				(type default)
			)
			(layer "B.Fab")
		)
		(fp_line
			(start -0.299974 0.150114)
			(end 0.299974 0.150114)
			(stroke
				(width 0.1)
				(type default)
			)
			(layer "B.Fab")
		)
		(pad "1" smd rect
			(at 0.2667 0 270)
			(size 0.3048 0.381)
			(layers "B.Cu" "B.Mask" "B.Paste")
			(net "P0V9_CPU0_RT0_2A")
		)
		(pad "2" smd rect
			(at -0.2667 0 270)
			(size 0.3048 0.381)
			(layers "B.Cu" "B.Mask" "B.Paste")
			(net "GND")
		)
	)
)
